(kicad_pcb
	(version 20260206)
	(generator "pcbnew")
	(generator_version "10.0")
	(general
		(thickness 1.6)
		(legacy_teardrops no)
	)
	(paper "A4")
	(title_block
		(title "03242023_DA0F0TMBIJ0_F0T_Motherboard_J_brd_V01_OCP.brd")
		(comment 1 "Grand Teton / footprints 2065-2071 of 6105")
	)
	(layers
		(0 "F.Cu" signal "TOP")
		(4 "In1.Cu" signal "GND")
		(6 "In2.Cu" signal "IN1")
		(8 "In3.Cu" signal "GND1")
		(10 "In4.Cu" signal "IN2")
		(12 "In5.Cu" signal "GND2")
		(14 "In6.Cu" signal "IN3")
		(16 "In7.Cu" signal "GND3")
		(18 "In8.Cu" signal "VCC")
		(20 "In9.Cu" signal "VCC1")
		(22 "In10.Cu" signal "GND4")
		(24 "In11.Cu" signal "IN4")
		(26 "In12.Cu" signal "GND5")
		(28 "In13.Cu" signal "IN5")
		(30 "In14.Cu" signal "GND6")
		(32 "In15.Cu" signal "IN6")
		(34 "In16.Cu" signal "GND7")
		(2 "B.Cu" signal "BOTTOM")
		(9 "F.Adhes" user "F.Adhesive")
		(11 "B.Adhes" user "B.Adhesive")
		(13 "F.Paste" user "Package Geometry/Pastemask Top")
		(15 "B.Paste" user "Package Geometry/Pastemask Bottom")
		(5 "F.SilkS" user "Ref Des/Silkscreen Top")
		(7 "B.SilkS" user "Ref Des/Silkscreen Bottom")
		(1 "F.Mask" user "Board Geometry/Soldermask Top")
		(3 "B.Mask" user "Board Geometry/Soldermask Bottom")
		(17 "Dwgs.User" user "User.Drawings")
		(19 "Cmts.User" user "User.Comments")
		(21 "Eco1.User" user "User.Eco1")
		(23 "Eco2.User" user "User.Eco2")
		(25 "Edge.Cuts" user "Board Geometry/Outline")
		(27 "Margin" user)
		(31 "F.CrtYd" user "Package Geometry/Place Bound Top")
		(29 "B.CrtYd" user "Package Geometry/Place Bound Bottom")
		(35 "F.Fab" user "Ref Des/Assembly Top")
		(33 "B.Fab" user "Ref Des/Assembly Bottom")
	)
	(footprint ""
		(layer "F.Cu")
		(at 24.050752 -403.822408 180)
		(property "Reference" "R3511"
			(at 0 0 180)
			(layer "F.SilkS")
			(hide yes)
			(effects
				(font
					(size 1.27 1.27)
				)
			)
		)
		(property "Value" ""
			(at 0 0 180)
			(layer "F.Fab")
			(effects
				(font
					(size 1.27 1.27)
				)
			)
		)
		(duplicate_pad_numbers_are_jumpers no)
		(fp_line
			(start 0.7874 0.4064)
			(end -0.7874 0.4064)
			(stroke
				(width 0.1524)
				(type default)
			)
			(layer "F.SilkS")
		)
		(fp_line
			(start 0.7874 -0.4064)
			(end 0.7874 0.4064)
			(stroke
				(width 0.1524)
				(type default)
			)
			(layer "F.SilkS")
		)
		(fp_line
			(start -0.7874 0.4064)
			(end -0.7874 -0.4064)
			(stroke
				(width 0.1524)
				(type default)
			)
			(layer "F.SilkS")
		)
		(fp_line
			(start -0.7874 -0.4064)
			(end 0.7874 -0.4064)
			(stroke
				(width 0.1524)
				(type default)
			)
			(layer "F.SilkS")
		)
		(fp_line
			(start 0.67945 0.3048)
			(end 0.120396 0.3048)
			(stroke
				(width 0.1)
				(type default)
			)
			(layer "F.Fab")
		)
		(fp_line
			(start 0.67945 -0.3048)
			(end 0.67945 0.3048)
			(stroke
				(width 0.1)
				(type default)
			)
			(layer "F.Fab")
		)
		(fp_line
			(start 0.12065 -0.2794)
			(end 0.12065 -0.3048)
			(stroke
				(width 0.1)
				(type default)
			)
			(layer "F.Fab")
		)
		(fp_line
			(start 0.12065 -0.3048)
			(end 0.67945 -0.3048)
			(stroke
				(width 0.1)
				(type default)
			)
			(layer "F.Fab")
		)
		(fp_line
			(start 0.120396 0.3048)
			(end 0.120396 0.2794)
			(stroke
				(width 0.1)
				(type default)
			)
			(layer "F.Fab")
		)
		(fp_line
			(start 0.120396 0.2794)
			(end -0.12065 0.2794)
			(stroke
				(width 0.1)
				(type default)
			)
			(layer "F.Fab")
		)
		(fp_line
			(start -0.12065 0.3048)
			(end -0.67945 0.3048)
			(stroke
				(width 0.1)
				(type default)
			)
			(layer "F.Fab")
		)
		(fp_line
			(start -0.12065 0.2794)
			(end -0.12065 0.3048)
			(stroke
				(width 0.1)
				(type default)
			)
			(layer "F.Fab")
		)
		(fp_line
			(start -0.12065 -0.2794)
			(end 0.12065 -0.2794)
			(stroke
				(width 0.1)
				(type default)
			)
			(layer "F.Fab")
		)
		(fp_line
			(start -0.12065 -0.305054)
			(end -0.12065 -0.2794)
			(stroke
				(width 0.1)
				(type default)
			)
			(layer "F.Fab")
		)
		(fp_line
			(start -0.67945 0.3048)
			(end -0.67945 -0.305054)
			(stroke
				(width 0.1)
				(type default)
			)
			(layer "F.Fab")
		)
		(fp_line
			(start -0.67945 -0.305054)
			(end -0.12065 -0.305054)
			(stroke
				(width 0.1)
				(type default)
			)
			(layer "F.Fab")
		)
		(pad "1" smd circle
			(at -0.40005 0 180)
			(size 0 0)
			(layers "F.Cu" "F.Mask" "F.Paste")
			(net "GPU_FPGA_READY")
		)
		(pad "2" smd circle
			(at 0.40005 0 180)
			(size 0 0)
			(layers "F.Cu" "F.Mask" "F.Paste")
			(net "GND")
		)
	)
	(footprint ""
		(layer "F.Cu")
		(at 278.414734 -19.279108 180)
		(property "Reference" "U217"
			(at 1.229868 1.844548 0)
			(unlocked yes)
			(layer "F.SilkS")
			(effects
				(font
					(size 0.7874 0.5842)
					(thickness 0.1524)
				)
				(justify left)
			)
		)
		(property "Value" ""
			(at 0 0 180)
			(layer "F.Fab")
			(effects
				(font
					(size 1.27 1.27)
				)
			)
		)
		(duplicate_pad_numbers_are_jumpers no)
		(fp_line
			(start 1.400048 1.100074)
			(end -1.400048 1.100074)
			(stroke
				(width 0.1524)
				(type default)
			)
			(layer "F.SilkS")
		)
		(fp_line
			(start 1.400048 -1.100074)
			(end 1.400048 1.100074)
			(stroke
				(width 0.1524)
				(type default)
			)
			(layer "F.SilkS")
		)
		(fp_line
			(start 1.400048 -1.100074)
			(end -1.400048 -1.100074)
			(stroke
				(width 0.1524)
				(type default)
			)
			(layer "F.SilkS")
		)
		(fp_line
			(start -1.400048 1.100074)
			(end -1.400048 -1.100074)
			(stroke
				(width 0.1524)
				(type default)
			)
			(layer "F.SilkS")
		)
		(fp_poly
			(pts
				(xy -1.02362 -1.291082) (xy -1.53162 -2.307082) (xy -0.51562 -2.307082)
			)
			(stroke
				(width 0)
				(type default)
			)
			(fill yes)
			(layer "F.SilkS")
		)
		(fp_line
			(start 0.674878 1.100074)
			(end -0.674878 1.100074)
			(stroke
				(width 0.1)
				(type default)
			)
			(layer "F.Fab")
		)
		(fp_line
			(start 0.674878 -1.100074)
			(end 0.674878 1.100074)
			(stroke
				(width 0.1)
				(type default)
			)
			(layer "F.Fab")
		)
		(fp_line
			(start -0.674878 1.100074)
			(end -0.674878 -1.100074)
			(stroke
				(width 0.1)
				(type default)
			)
			(layer "F.Fab")
		)
		(fp_line
			(start -0.674878 -1.100074)
			(end 0.674878 -1.100074)
			(stroke
				(width 0.1)
				(type default)
			)
			(layer "F.Fab")
		)
		(fp_poly
			(pts
				(xy -1.590548 -0.649986) (xy -2.606548 -1.157986) (xy -2.606548 -0.141986)
			)
			(stroke
				(width 0)
				(type default)
			)
			(fill yes)
			(layer "F.Fab")
		)
		(pad "1" smd rect
			(at -0.94996 -0.649986 90)
			(size 0.4318 0.6096)
			(layers "F.Cu" "F.Mask" "F.Paste")
			(net "PU_OCP_V3_2_WAKE_OE")
		)
		(pad "2" smd rect
			(at -0.94996 0 90)
			(size 0.4318 0.6096)
			(layers "F.Cu" "F.Mask" "F.Paste")
			(net "IRQ_LVC3_OCP_V3_2_WAKE_N")
		)
		(pad "3" smd rect
			(at -0.94996 0.649986 90)
			(size 0.4318 0.6096)
			(layers "F.Cu" "F.Mask" "F.Paste")
			(net "GND")
		)
		(pad "4" smd rect
			(at 0.94996 0.649986 90)
			(size 0.4318 0.6096)
			(layers "F.Cu" "F.Mask" "F.Paste")
			(net "OCP_V3_2_WAKE_BUFF_N")
		)
		(pad "5" smd rect
			(at 0.94996 -0.649986 90)
			(size 0.4318 0.6096)
			(layers "F.Cu" "F.Mask" "F.Paste")
			(net "P3V3_AUX")
		)
	)
	(footprint ""
		(layer "F.Cu")
		(at 201.047604 -35.025838 90)
		(property "Reference" "R3635"
			(at 0 0 90)
			(layer "F.SilkS")
			(hide yes)
			(effects
				(font
					(size 1.27 1.27)
				)
			)
		)
		(property "Value" ""
			(at 0 0 90)
			(layer "F.Fab")
			(effects
				(font
					(size 1.27 1.27)
				)
			)
		)
		(duplicate_pad_numbers_are_jumpers no)
		(fp_line
			(start 4.0386 -1.7526)
			(end 4.0386 1.7526)
			(stroke
				(width 0.1524)
				(type default)
			)
			(layer "F.SilkS")
		)
		(fp_line
			(start -4.0386 -1.7526)
			(end 4.0386 -1.7526)
			(stroke
				(width 0.1524)
				(type default)
			)
			(layer "F.SilkS")
		)
		(fp_line
			(start 4.0386 1.7526)
			(end -4.0386 1.7526)
			(stroke
				(width 0.1524)
				(type default)
			)
			(layer "F.SilkS")
		)
		(fp_line
			(start -4.0386 1.7526)
			(end -4.0386 -1.7526)
			(stroke
				(width 0.1524)
				(type default)
			)
			(layer "F.SilkS")
		)
		(fp_line
			(start 4.0386 -1.7526)
			(end 4.0386 1.7526)
			(stroke
				(width 0.1)
				(type default)
			)
			(layer "F.Fab")
		)
		(fp_line
			(start -4.0386 -1.7526)
			(end 4.0386 -1.7526)
			(stroke
				(width 0.1)
				(type default)
			)
			(layer "F.Fab")
		)
		(fp_line
			(start 4.0386 1.7526)
			(end -4.0386 1.7526)
			(stroke
				(width 0.1)
				(type default)
			)
			(layer "F.Fab")
		)
		(fp_line
			(start -4.0386 1.7526)
			(end -4.0386 -1.7526)
			(stroke
				(width 0.1)
				(type default)
			)
			(layer "F.Fab")
		)
		(pad "1" smd rect
			(at -3.1115 0 90)
			(size 1.524 3.2004)
			(layers "F.Cu" "F.Mask" "F.Paste")
			(net "P12V_SCM")
		)
		(pad "2" smd rect
			(at 3.1115 0 90)
			(size 1.524 3.2004)
			(layers "F.Cu" "F.Mask" "F.Paste")
			(net "P12V_SCM_R")
		)
	)
	(footprint ""
		(layer "F.Cu")
		(at 35.066478 -17.623536 90)
		(property "Reference" "C820"
			(at 0 0 90)
			(layer "F.SilkS")
			(hide yes)
			(effects
				(font
					(size 1.27 1.27)
				)
			)
		)
		(property "Value" ""
			(at 0 0 90)
			(layer "F.Fab")
			(effects
				(font
					(size 1.27 1.27)
				)
			)
		)
		(duplicate_pad_numbers_are_jumpers no)
		(fp_line
			(start 0.299974 -0.150114)
			(end 0.299974 0.150114)
			(stroke
				(width 0.1)
				(type default)
			)
			(layer "F.Fab")
		)
		(fp_line
			(start -0.299974 -0.150114)
			(end 0.299974 -0.150114)
			(stroke
				(width 0.1)
				(type default)
			)
			(layer "F.Fab")
		)
		(fp_line
			(start 0.299974 0.150114)
			(end -0.299974 0.150114)
			(stroke
				(width 0.1)
				(type default)
			)
			(layer "F.Fab")
		)
		(fp_line
			(start -0.299974 0.150114)
			(end -0.299974 -0.150114)
			(stroke
				(width 0.1)
				(type default)
			)
			(layer "F.Fab")
		)
		(pad "1" smd rect
			(at -0.2667 0 90)
			(size 0.3048 0.381)
			(layers "F.Cu" "F.Mask" "F.Paste")
			(net "P5E_CPU1_PE1_TX_C_DN<8>")
		)
		(pad "2" smd rect
			(at 0.2667 0 90)
			(size 0.3048 0.381)
			(layers "F.Cu" "F.Mask" "F.Paste")
			(net "P5E_CPU1_PE1_TX_DN<8>")
		)
	)
	(footprint ""
		(layer "F.Cu")
		(at 277.6347 -95.029274)
		(property "Reference" "R717"
			(at 0 0 0)
			(layer "F.SilkS")
			(hide yes)
			(effects
				(font
					(size 1.27 1.27)
				)
			)
		)
		(property "Value" ""
			(at 0 0 0)
			(layer "F.Fab")
			(effects
				(font
					(size 1.27 1.27)
				)
			)
		)
		(duplicate_pad_numbers_are_jumpers no)
		(fp_line
			(start -0.7874 -0.4064)
			(end 0.7874 -0.4064)
			(stroke
				(width 0.1524)
				(type default)
			)
			(layer "F.SilkS")
		)
		(fp_line
			(start -0.7874 0.4064)
			(end -0.7874 -0.4064)
			(stroke
				(width 0.1524)
				(type default)
			)
			(layer "F.SilkS")
		)
		(fp_line
			(start 0.7874 -0.4064)
			(end 0.7874 0.4064)
			(stroke
				(width 0.1524)
				(type default)
			)
			(layer "F.SilkS")
		)
		(fp_line
			(start 0.7874 0.4064)
			(end -0.7874 0.4064)
			(stroke
				(width 0.1524)
				(type default)
			)
			(layer "F.SilkS")
		)
		(fp_line
			(start -0.67945 -0.305054)
			(end -0.12065 -0.305054)
			(stroke
				(width 0.1)
				(type default)
			)
			(layer "F.Fab")
		)
		(fp_line
			(start -0.67945 0.3048)
			(end -0.67945 -0.305054)
			(stroke
				(width 0.1)
				(type default)
			)
			(layer "F.Fab")
		)
		(fp_line
			(start -0.12065 -0.305054)
			(end -0.12065 -0.2794)
			(stroke
				(width 0.1)
				(type default)
			)
			(layer "F.Fab")
		)
		(fp_line
			(start -0.12065 -0.2794)
			(end 0.12065 -0.2794)
			(stroke
				(width 0.1)
				(type default)
			)
			(layer "F.Fab")
		)
		(fp_line
			(start -0.12065 0.2794)
			(end -0.12065 0.3048)
			(stroke
				(width 0.1)
				(type default)
			)
			(layer "F.Fab")
		)
		(fp_line
			(start -0.12065 0.3048)
			(end -0.67945 0.3048)
			(stroke
				(width 0.1)
				(type default)
			)
			(layer "F.Fab")
		)
		(fp_line
			(start 0.120396 0.2794)
			(end -0.12065 0.2794)
			(stroke
				(width 0.1)
				(type default)
			)
			(layer "F.Fab")
		)
		(fp_line
			(start 0.120396 0.3048)
			(end 0.120396 0.2794)
			(stroke
				(width 0.1)
				(type default)
			)
			(layer "F.Fab")
		)
		(fp_line
			(start 0.12065 -0.3048)
			(end 0.67945 -0.3048)
			(stroke
				(width 0.1)
				(type default)
			)
			(layer "F.Fab")
		)
		(fp_line
			(start 0.12065 -0.2794)
			(end 0.12065 -0.3048)
			(stroke
				(width 0.1)
				(type default)
			)
			(layer "F.Fab")
		)
		(fp_line
			(start 0.67945 -0.3048)
			(end 0.67945 0.3048)
			(stroke
				(width 0.1)
				(type default)
			)
			(layer "F.Fab")
		)
		(fp_line
			(start 0.67945 0.3048)
			(end 0.120396 0.3048)
			(stroke
				(width 0.1)
				(type default)
			)
			(layer "F.Fab")
		)
		(pad "1" smd circle
			(at -0.40005 0)
			(size 0 0)
			(layers "F.Cu" "F.Mask" "F.Paste")
			(net "P3V3_AUX")
		)
		(pad "2" smd circle
			(at 0.40005 0)
			(size 0 0)
			(layers "F.Cu" "F.Mask" "F.Paste")
			(net "MB_FRU_ADDR1")
		)
	)
	(footprint ""
		(layer "F.Cu")
		(at 30.765242 -179.587906)
		(property "Reference" "PL121"
			(at -1.874012 5.29082 0)
			(unlocked yes)
			(layer "F.SilkS")
			(effects
				(font
					(size 0.7874 0.5842)
					(thickness 0.1524)
				)
				(justify left)
			)
		)
		(property "Value" ""
			(at 0 0 0)
			(layer "F.Fab")
			(effects
				(font
					(size 1.27 1.27)
				)
			)
		)
		(duplicate_pad_numbers_are_jumpers no)
		(fp_line
			(start -3.6576 -3.350006)
			(end 3.64998 -3.350006)
			(stroke
				(width 0.1524)
				(type default)
			)
			(layer "F.SilkS")
		)
		(fp_line
			(start -3.64998 -1.8034)
			(end -3.64998 -3.350006)
			(stroke
				(width 0.1524)
				(type default)
			)
			(layer "F.SilkS")
		)
		(fp_line
			(start -3.64998 3.350006)
			(end -3.64998 1.8288)
			(stroke
				(width 0.1524)
				(type default)
			)
			(layer "F.SilkS")
		)
		(fp_line
			(start 3.64998 -3.350006)
			(end 3.64998 -1.8034)
			(stroke
				(width 0.1524)
				(type default)
			)
			(layer "F.SilkS")
		)
		(fp_line
			(start 3.64998 1.8034)
			(end 3.64998 3.350006)
			(stroke
				(width 0.1524)
				(type default)
			)
			(layer "F.SilkS")
		)
		(fp_line
			(start 3.64998 3.350006)
			(end -3.64998 3.350006)
			(stroke
				(width 0.1524)
				(type default)
			)
			(layer "F.SilkS")
		)
		(fp_line
			(start -3.64998 -3.350006)
			(end 3.64998 -3.350006)
			(stroke
				(width 0.1)
				(type default)
			)
			(layer "F.Fab")
		)
		(fp_line
			(start -3.64998 3.350006)
			(end -3.64998 -3.350006)
			(stroke
				(width 0.1)
				(type default)
			)
			(layer "F.Fab")
		)
		(fp_line
			(start 3.64998 -3.350006)
			(end 3.64998 3.350006)
			(stroke
				(width 0.1)
				(type default)
			)
			(layer "F.Fab")
		)
		(fp_line
			(start 3.64998 3.350006)
			(end -3.64998 3.350006)
			(stroke
				(width 0.1)
				(type default)
			)
			(layer "F.Fab")
		)
		(pad "1" smd rect
			(at -2.92481 0)
			(size 2.15392 3.302)
			(layers "F.Cu" "F.Mask" "F.Paste")
			(net "SW_PVNN_MAIN_CPU1_SW")
		)
		(pad "2" smd rect
			(at 2.92481 0)
			(size 2.15392 3.302)
			(layers "F.Cu" "F.Mask" "F.Paste")
			(net "PVNN_MAIN_CPU1")
		)
	)
	(footprint ""
		(layer "F.Cu")
		(at 187.28436 -29.77769 -90)
		(property "Reference" "PC2230"
			(at 0 0 270)
			(layer "F.SilkS")
			(hide yes)
			(effects
				(font
					(size 1.27 1.27)
				)
			)
		)
		(property "Value" ""
			(at 0 0 270)
			(layer "F.Fab")
			(effects
				(font
					(size 1.27 1.27)
				)
			)
		)
		(duplicate_pad_numbers_are_jumpers no)
		(fp_line
			(start -0.7874 0.4064)
			(end -0.7874 -0.4064)
			(stroke
				(width 0.1524)
				(type default)
			)
			(layer "F.SilkS")
		)
		(fp_line
			(start 0.7874 0.4064)
			(end -0.7874 0.4064)
			(stroke
				(width 0.1524)
				(type default)
			)
			(layer "F.SilkS")
		)
		(fp_line
			(start -0.7874 -0.4064)
			(end 0.7874 -0.4064)
			(stroke
				(width 0.1524)
				(type default)
			)
			(layer "F.SilkS")
		)
		(fp_line
			(start 0.7874 -0.4064)
			(end 0.7874 0.4064)
			(stroke
				(width 0.1524)
				(type default)
			)
			(layer "F.SilkS")
		)
		(fp_line
			(start -0.67945 0.3048)
			(end -0.67945 -0.305054)
			(stroke
				(width 0.1)
				(type default)
			)
			(layer "F.Fab")
		)
		(fp_line
			(start -0.12065 0.3048)
			(end -0.67945 0.3048)
			(stroke
				(width 0.1)
				(type default)
			)
			(layer "F.Fab")
		)
		(fp_line
			(start 0.120396 0.3048)
			(end 0.120396 0.2794)
			(stroke
				(width 0.1)
				(type default)
			)
			(layer "F.Fab")
		)
		(fp_line
			(start 0.67945 0.3048)
			(end 0.120396 0.3048)
			(stroke
				(width 0.1)
				(type default)
			)
			(layer "F.Fab")
		)
		(fp_line
			(start -0.12065 0.2794)
			(end -0.12065 0.3048)
			(stroke
				(width 0.1)
				(type default)
			)
			(layer "F.Fab")
		)
		(fp_line
			(start 0.120396 0.2794)
			(end -0.12065 0.2794)
			(stroke
				(width 0.1)
				(type default)
			)
			(layer "F.Fab")
		)
		(fp_line
			(start -0.12065 -0.2794)
			(end 0.12065 -0.2794)
			(stroke
				(width 0.1)
				(type default)
			)
			(layer "F.Fab")
		)
		(fp_line
			(start 0.12065 -0.2794)
			(end 0.12065 -0.3048)
			(stroke
				(width 0.1)
				(type default)
			)
			(layer "F.Fab")
		)
		(fp_line
			(start 0.12065 -0.3048)
			(end 0.67945 -0.3048)
			(stroke
				(width 0.1)
				(type default)
			)
			(layer "F.Fab")
		)
		(fp_line
			(start 0.67945 -0.3048)
			(end 0.67945 0.3048)
			(stroke
				(width 0.1)
				(type default)
			)
			(layer "F.Fab")
		)
		(fp_line
			(start -0.67945 -0.305054)
			(end -0.12065 -0.305054)
			(stroke
				(width 0.1)
				(type default)
			)
			(layer "F.Fab")
		)
		(fp_line
			(start -0.12065 -0.305054)
			(end -0.12065 -0.2794)
			(stroke
				(width 0.1)
				(type default)
			)
			(layer "F.Fab")
		)
		(pad "1" smd circle
			(at -0.40005 0 270)
			(size 0 0)
			(layers "F.Cu" "F.Mask" "F.Paste")
			(net "P12V_AUX")
		)
		(pad "2" smd circle
			(at 0.40005 0 270)
			(size 0 0)
			(layers "F.Cu" "F.Mask" "F.Paste")
			(net "GND")
		)
	)
)
